FILE_TYPE = CONNECTIVITY;
{Allegro Design Entry HDL 17.2-2016 S081 (4005846) 1/11/2022}
"PAGE_NUMBER" = 161;
0"NC";
1"P3V3_AUX\g";
2"P3V3_AUX\g";
3"P3V3_AUX\g";
4"P3V3_AUX\g";
5"P3V3_AUX\g"VOLTAGE"3.3";
6"P3V3_AUX\g";
7"P3V3_AUX\g"VOLTAGE"3.3";
8"P3V3_AUX\g";
9"P3V3_AUX\g";
10"P3V3_AUX\g";
11"P3V3_AUX\g";
12"P3V3_AUX\g";
13"GND\g";
14"GND\g";
15"GND\g";
16"GND\g";
17"GND\g";
18"GND\g";
19"GND\g";
20"GND\g";
21"GND\g";
22"GND\g";
23"GND\g";
24"GND\g";
25"GND\g";
26"GND\g";
27"GND\g";
28"GND\g";
29"GND\g";
30"GND\g";
31"GND\g";
32"GND\g";
33"FM_THERMAL_ALERT_N";
34"FM_THERMAL_ALERT_N";
35"FM_THERMAL_ALERT_N";
36"SMB_LM75_0_3V3AUX_SDA";
37"FM_THERMAL_ALERT_N";
38"SMB_LM75_0_3V3AUX_SDA_R1";
39"FM_G751_0_ALERT_N";
40"SMB_LM75_0_3V3AUX_SCL_R1";
41"SMB_LM75_1_3V3AUX_SDA";
42"U271_1_ADD0"CDS_PHYS_NET_NAME"TCA9539_0_ADD0";
43"SMB_LM75_1_3V3AUX_SCL_R1";
44"SMB_LM75_1_3V3AUX_SDA_R1";
45"FM_LM75_2_ALERT_N";
46"SMB_LM75_2_3V3AUX_SDA_R1";
47"FM_G751_1_ALERT_N";
48"SMB_LM75_3_3V3AUX_SDA";
49"SMB_LM75_3_3V3AUX_SCL_R1";
50"SMB_LM75_3_3V3AUX_SDA_R1";
51"U273_3_ADD0"CDS_PHYS_NET_NAME"TCA9539_0_ADD0";
52"U273_3_ADD1"CDS_PHYS_NET_NAME"TCA9539_0_ADD1";
53"U273_3_ADD2"CDS_PHYS_NET_NAME"TCA9539_0_ADD1";
54"FM_LM75_3_ALERT_N";
55"SMB_LM75_3_3V3AUX_SCL";
56"SMB_LM75_2_3V3AUX_SCL_R1";
57"U272_2_ADD1"CDS_PHYS_NET_NAME"TCA9539_0_ADD1";
58"U272_2_ADD2"CDS_PHYS_NET_NAME"TCA9539_0_ADD1";
59"U272_2_ADD0"CDS_PHYS_NET_NAME"TCA9539_0_ADD0";
60"SMB_LM75_2_3V3AUX_SDA";
61"SMB_LM75_2_3V3AUX_SCL";
62"U271_1_ADD2"CDS_PHYS_NET_NAME"TCA9539_0_ADD1";
63"U271_1_ADD1"CDS_PHYS_NET_NAME"TCA9539_0_ADD1";
64"SMB_LM75_1_3V3AUX_SCL";
65"U270_0_ADD1"CDS_PHYS_NET_NAME"TCA9539_0_ADD1";
66"U270_0_ADD2"CDS_PHYS_NET_NAME"TCA9539_0_ADD1";
67"U270_0_ADD0"CDS_PHYS_NET_NAME"TCA9539_0_ADD0";
68"SMB_LM75_0_3V3AUX_SCL";
%"UNIVERSAL_POWER"
"1","(2550,800)","0","logical_power","I100";
;
HDL_POWER"P3V3_AUX"
CDS_LIB"logical_power";
"A"8;
%"Q_RES"
"2","(3900,125)","0","pure_quanta","I101";
;
PART_NUMBER"CS21002FB06"
TOLERANCE"1%"
WATTAGE"1/16W"
VALUE"1K"
MATERIAL"EMPTY"
PACK_TYPE"0402LF"
$LOCATION"R4188"
CDS_LIB"pure_quanta"
CDS_LOCATION"R4188"
$SEC"1"
CDS_SEC"1";
"A"
$PN"1"10;
"B"
$PN"2"62;
%"Q_RES"
"2","(3900,-475)","0","pure_quanta","I102";
;
PART_NUMBER"CS21002FB06"
MATERIAL"CHIP"
PACK_TYPE"0402LF"
VALUE"1K"
WATTAGE"1/16W"
TOLERANCE"1%"
$LOCATION"R4189"
CDS_LIB"pure_quanta"
CDS_LOCATION"R4189"
$SEC"1"
CDS_SEC"1";
"A"
$PN"1"62;
"B"
$PN"2"23;
%"UNIVERSAL_GND"
"1","(3900,-700)","0","logical_power","I103";
;
CDS_LIB"logical_power"
HDL_POWER"GND";
"A"23;
%"Q_CAP"
"1","(2550,475)","2","pure_quanta","I104";
;
PART_NUMBER"CH4104K1B00"
PACK_TYPE"0402"
TOLERANCE"10%"
MATERIAL"X7R"
VALUE"0.1UF"
VOLTAGE"25V"
$LOCATION"C2276"
CDS_LIB"pure_quanta"
CDS_LOCATION"C2276"
$SEC"1"
CDS_SEC"1";
"B"
$PN"2"24;
"A"
$PN"1"8;
%"UNIVERSAL_GND"
"1","(2550,250)","0","logical_power","I105";
;
CDS_LIB"logical_power"
HDL_POWER"GND";
"A"24;
%"UNIVERSAL_GND"
"1","(1625,-450)","0","logical_power","I106";
;
HDL_POWER"GND"
CDS_LIB"logical_power";
"A"15;
%"Q_RES"
"1","(300,125)","0","pure_quanta","I107";
;
PART_NUMBER"CS03322FB03"
WATTAGE"1/16W"
MATERIAL"CHIP"
TOLERANCE"1%"
VALUE"33.2"
PACK_TYPE"0402LF"
$LOCATION"R4182"
CDS_LIB"pure_quanta"
CDS_LOCATION"R4182"
$SEC"1"
CDS_SEC"1";
"B"
$PN"2"44;
"A"
$PN"1"41;
%"Q_RES"
"1","(300,-175)","0","pure_quanta","I108";
;
PART_NUMBER"CS00002JB13"
VALUE"0"
PACK_TYPE"0402LF"
MATERIAL"CHIP"
$LOCATION"R4214"
CDS_LIB"pure_quanta"
WATTAGE"1/16W"
TOLERANCE"5%"
CDS_LOCATION"R4214"
$SEC"1"
CDS_SEC"1";
"B"
$PN"2"47;
"A"
$PN"1"35;
%"Q_RES"
"1","(300,-25)","0","pure_quanta","I109";
;
PART_NUMBER"CS03322FB03"
MATERIAL"CHIP"
VALUE"33.2"
TOLERANCE"1%"
WATTAGE"1/16W"
PACK_TYPE"0402LF"
$LOCATION"R4179"
CDS_LIB"pure_quanta"
CDS_LOCATION"R4179"
$SEC"1"
CDS_SEC"1";
"B"
$PN"2"43;
"A"
$PN"1"64;
%"Q_RES"
"1","(275,-1500)","0","pure_quanta","I114";
;
PART_NUMBER"CS03322FB03"
TOLERANCE"1%"
WATTAGE"1/16W"
MATERIAL"CHIP"
PACK_TYPE"0402LF"
VALUE"33.2"
$LOCATION"R4178"
CDS_LIB"pure_quanta"
CDS_LOCATION"R4178"
$SEC"1"
CDS_SEC"1";
"B"
$PN"2"56;
"A"
$PN"1"61;
%"Q_RES"
"1","(275,-1650)","0","pure_quanta","I115";
;
PART_NUMBER"CS00002JB13"
MATERIAL"CHIP"
VALUE"0"
PACK_TYPE"0402LF"
$LOCATION"R4213"
TOLERANCE"5%"
WATTAGE"1/16W"
CDS_LIB"pure_quanta"
CDS_LOCATION"R4213"
$SEC"1"
CDS_SEC"1";
"B"
$PN"2"45;
"A"
$PN"1"34;
%"Q_RES"
"1","(275,-1350)","0","pure_quanta","I116";
;
PART_NUMBER"CS03322FB03"
MATERIAL"CHIP"
VALUE"33.2"
TOLERANCE"1%"
WATTAGE"1/16W"
PACK_TYPE"0402LF"
$LOCATION"R4181"
CDS_LIB"pure_quanta"
CDS_LOCATION"R4181"
$SEC"1"
CDS_SEC"1";
"B"
$PN"2"46;
"A"
$PN"1"60;
%"UNIVERSAL_GND"
"1","(1600,-1925)","0","logical_power","I117";
;
CDS_LIB"logical_power"
HDL_POWER"GND";
"A"14;
%"UNIVERSAL_GND"
"1","(2525,-1225)","0","logical_power","I118";
;
HDL_POWER"GND"
CDS_LIB"logical_power";
"A"28;
%"Q_CAP"
"1","(2525,-1000)","2","pure_quanta","I119";
;
PART_NUMBER"CH4104K1B00"
MATERIAL"X7R"
VOLTAGE"25V"
VALUE"0.1UF"
PACK_TYPE"0402"
TOLERANCE"10%"
$LOCATION"C2275"
CDS_LIB"pure_quanta"
CDS_LOCATION"C2275"
$SEC"1"
CDS_SEC"1";
"B"
$PN"2"28;
"A"
$PN"1"7;
%"UNIVERSAL_GND"
"1","(3875,-2175)","0","logical_power","I120";
;
HDL_POWER"GND"
CDS_LIB"logical_power";
"A"27;
%"Q_RES"
"2","(3875,-1950)","0","pure_quanta","I121";
;
PART_NUMBER"CS21002FB06"
TOLERANCE"1%"
WATTAGE"1/16W"
VALUE"1K"
PACK_TYPE"0402LF"
MATERIAL"CHIP"
$LOCATION"R4187"
CDS_LIB"pure_quanta"
CDS_LOCATION"R4187"
$SEC"1"
CDS_SEC"1";
"A"
$PN"1"58;
"B"
$PN"2"27;
%"Q_RES"
"2","(3875,-1350)","0","pure_quanta","I122";
;
PART_NUMBER"CS21002FB06"
PACK_TYPE"0402LF"
MATERIAL"EMPTY"
VALUE"1K"
WATTAGE"1/16W"
TOLERANCE"1%"
$LOCATION"R4186"
CDS_LIB"pure_quanta"
CDS_LOCATION"R4186"
$SEC"1"
CDS_SEC"1";
"A"
$PN"1"11;
"B"
$PN"2"58;
%"UNIVERSAL_POWER"
"1","(2525,-675)","0","logical_power","I123";
;
HDL_POWER"P3V3_AUX"
CDS_LIB"logical_power";
"A"7;
%"UNIVERSAL_GND"
"1","(4125,-2175)","0","logical_power","I124";
;
HDL_POWER"GND"
CDS_LIB"logical_power";
"A"26;
%"Q_RES"
"2","(4125,-1950)","0","pure_quanta","I125";
;
PART_NUMBER"CS21002FB06"
TOLERANCE"1%"
WATTAGE"1/16W"
VALUE"1K"
PACK_TYPE"0402LF"
MATERIAL"CHIP"
$LOCATION"R4195"
CDS_LIB"pure_quanta"
CDS_LOCATION"R4195"
$SEC"1"
CDS_SEC"1";
"A"
$PN"1"57;
"B"
$PN"2"26;
%"UNIVERSAL_GND"
"1","(4375,-2175)","0","logical_power","I126";
;
HDL_POWER"GND"
CDS_LIB"logical_power";
"A"25;
%"Q_RES"
"2","(4375,-1950)","0","pure_quanta","I127";
;
PART_NUMBER"CS21002FB06"
TOLERANCE"1%"
VALUE"1K"
WATTAGE"1/16W"
PACK_TYPE"0402LF"
MATERIAL"CHIP"
$LOCATION"R4203"
CDS_LIB"pure_quanta"
CDS_LOCATION"R4203"
$SEC"1"
CDS_SEC"1";
"A"
$PN"1"59;
"B"
$PN"2"25;
%"Q_RES"
"2","(4125,-1350)","0","pure_quanta","I128";
;
PART_NUMBER"CS21002FB06"
PACK_TYPE"0402LF"
MATERIAL"EMPTY"
VALUE"1K"
WATTAGE"1/16W"
TOLERANCE"1%"
$LOCATION"R4194"
CDS_LIB"pure_quanta"
CDS_LOCATION"R4194"
$SEC"1"
CDS_SEC"1";
"A"
$PN"1"11;
"B"
$PN"2"57;
%"Q_RES"
"2","(4375,-1350)","0","pure_quanta","I129";
;
PART_NUMBER"CS21002FB06"
MATERIAL"EMPTY"
TOLERANCE"1%"
PACK_TYPE"0402LF"
VALUE"1K"
WATTAGE"1/16W"
$LOCATION"R4202"
CDS_LIB"pure_quanta"
CDS_LOCATION"R4202"
$SEC"1"
CDS_SEC"1";
"A"
$PN"1"11;
"B"
$PN"2"59;
%"UNIVERSAL_POWER"
"1","(4375,-925)","0","logical_power","I130";
;
HDL_POWER"P3V3_AUX"
CDS_LIB"logical_power";
"A"11;
%"Q_RES"
"1","(225,-2975)","0","pure_quanta","I134";
;
PART_NUMBER"CS03322FB03"
MATERIAL"CHIP"
PACK_TYPE"0402LF"
VALUE"33.2"
WATTAGE"1/16W"
TOLERANCE"1%"
$LOCATION"R3553"
CDS_LIB"pure_quanta"
CDS_LOCATION"R3553"
$SEC"1"
CDS_SEC"1";
"B"
$PN"2"49;
"A"
$PN"1"55;
%"Q_RES"
"1","(225,-3125)","0","pure_quanta","I135";
;
PART_NUMBER"CS00002JB13"
MATERIAL"CHIP"
PACK_TYPE"0402LF"
VALUE"0"
$LOCATION"R4212"
CDS_LIB"pure_quanta"
WATTAGE"1/16W"
TOLERANCE"5%"
CDS_LOCATION"R4212"
$SEC"1"
CDS_SEC"1";
"B"
$PN"2"54;
"A"
$PN"1"33;
%"Q_RES"
"1","(225,-2825)","0","pure_quanta","I136";
;
PART_NUMBER"CS03322FB03"
VALUE"33.2"
PACK_TYPE"0402LF"
TOLERANCE"1%"
MATERIAL"CHIP"
WATTAGE"1/16W"
$LOCATION"R3554"
CDS_LIB"pure_quanta"
CDS_LOCATION"R3554"
$SEC"1"
CDS_SEC"1";
"B"
$PN"2"50;
"A"
$PN"1"48;
%"UNIVERSAL_GND"
"1","(1550,-3400)","0","logical_power","I137";
;
CDS_LIB"logical_power"
HDL_POWER"GND";
"A"13;
%"UNIVERSAL_GND"
"1","(2475,-2700)","0","logical_power","I138";
;
CDS_LIB"logical_power"
HDL_POWER"GND";
"A"32;
%"Q_CAP"
"1","(2475,-2475)","2","pure_quanta","I139";
;
PART_NUMBER"CH4104K1B00"
VOLTAGE"25V"
MATERIAL"X7R"
PACK_TYPE"0402"
TOLERANCE"10%"
VALUE"0.1UF"
$LOCATION"C2274"
CDS_LIB"pure_quanta"
CDS_LOCATION"C2274"
$SEC"1"
CDS_SEC"1";
"B"
$PN"2"32;
"A"
$PN"1"5;
%"UNIVERSAL_GND"
"1","(3825,-3650)","0","logical_power","I140";
;
CDS_LIB"logical_power"
HDL_POWER"GND";
"A"31;
%"Q_RES"
"2","(3825,-3425)","0","pure_quanta","I141";
;
PART_NUMBER"CS21002FB06"
MATERIAL"CHIP"
PACK_TYPE"0402LF"
VALUE"1K"
WATTAGE"1/16W"
TOLERANCE"1%"
$LOCATION"R4185"
CDS_LIB"pure_quanta"
CDS_LOCATION"R4185"
$SEC"1"
CDS_SEC"1";
"A"
$PN"1"53;
"B"
$PN"2"31;
%"Q_RES"
"2","(3825,-2825)","0","pure_quanta","I142";
;
PART_NUMBER"CS21002FB06"
WATTAGE"1/16W"
VALUE"1K"
TOLERANCE"1%"
PACK_TYPE"0402LF"
MATERIAL"EMPTY"
$LOCATION"R4184"
CDS_LIB"pure_quanta"
CDS_LOCATION"R4184"
$SEC"1"
CDS_SEC"1";
"A"
$PN"1"4;
"B"
$PN"2"53;
%"UNIVERSAL_POWER"
"1","(2475,-2150)","0","logical_power","I143";
;
HDL_POWER"P3V3_AUX"
CDS_LIB"logical_power";
"A"5;
%"UNIVERSAL_GND"
"1","(4075,-3650)","0","logical_power","I144";
;
CDS_LIB"logical_power"
HDL_POWER"GND";
"A"30;
%"Q_RES"
"2","(4075,-3425)","0","pure_quanta","I145";
;
PART_NUMBER"CS21002FB06"
MATERIAL"CHIP"
PACK_TYPE"0402LF"
VALUE"1K"
WATTAGE"1/16W"
TOLERANCE"1%"
$LOCATION"R4193"
CDS_LIB"pure_quanta"
CDS_LOCATION"R4193"
$SEC"1"
CDS_SEC"1";
"A"
$PN"1"52;
"B"
$PN"2"30;
%"UNIVERSAL_GND"
"1","(4325,-3650)","0","logical_power","I146";
;
CDS_LIB"logical_power"
HDL_POWER"GND";
"A"29;
%"Q_RES"
"2","(4325,-3425)","0","pure_quanta","I147";
;
PART_NUMBER"CS21002FB06"
MATERIAL"CHIP"
PACK_TYPE"0402LF"
WATTAGE"1/16W"
VALUE"1K"
TOLERANCE"1%"
$LOCATION"R4201"
CDS_LIB"pure_quanta"
CDS_LOCATION"R4201"
$SEC"1"
CDS_SEC"1";
"A"
$PN"1"51;
"B"
$PN"2"29;
%"Q_RES"
"2","(4075,-2825)","0","pure_quanta","I148";
;
PART_NUMBER"CS21002FB06"
TOLERANCE"1%"
WATTAGE"1/16W"
VALUE"1K"
PACK_TYPE"0402LF"
MATERIAL"EMPTY"
$LOCATION"R4192"
CDS_LIB"pure_quanta"
CDS_LOCATION"R4192"
$SEC"1"
CDS_SEC"1";
"A"
$PN"1"4;
"B"
$PN"2"52;
%"Q_RES"
"2","(4325,-2825)","0","pure_quanta","I149";
;
PART_NUMBER"CS21002FB06"
WATTAGE"1/16W"
VALUE"1K"
PACK_TYPE"0402LF"
TOLERANCE"1%"
MATERIAL"EMPTY"
$LOCATION"R4200"
CDS_LIB"pure_quanta"
CDS_LOCATION"R4200"
$SEC"1"
CDS_SEC"1";
"A"
$PN"1"4;
"B"
$PN"2"51;
%"UNIVERSAL_POWER"
"1","(2600,2275)","0","logical_power","I15";
;
HDL_POWER"P3V3_AUX"
CDS_LIB"logical_power";
"A"12;
%"UNIVERSAL_POWER"
"1","(4325,-2400)","0","logical_power","I150";
;
HDL_POWER"P3V3_AUX"
CDS_LIB"logical_power";
"A"4;
%"UNIVERSAL_POWER"
"1","(-200,2025)","0","logical_power","I153";
;
HDL_POWER"P3V3_AUX"
CDS_LIB"logical_power";
"A"3;
%"UNIVERSAL_POWER"
"1","(-250,550)","0","logical_power","I154";
;
HDL_POWER"P3V3_AUX"
CDS_LIB"logical_power";
"A"2;
%"UNIVERSAL_POWER"
"1","(-250,-925)","0","logical_power","I156";
;
HDL_POWER"P3V3_AUX"
CDS_LIB"logical_power";
"A"6;
%"UNIVERSAL_POWER"
"1","(-350,-2350)","0","logical_power","I159";
;
HDL_POWER"P3V3_AUX"
CDS_LIB"logical_power";
"A"1;
%"Q_CAP"
"1","(2600,1950)","2","pure_quanta","I16";
;
PART_NUMBER"CH4104K1B00"
PACK_TYPE"0402"
VALUE"0.1UF"
VOLTAGE"25V"
TOLERANCE"10%"
MATERIAL"X7R"
$LOCATION"C2010"
CDS_LIB"pure_quanta"
CDS_LOCATION"C2010"
$SEC"1"
CDS_SEC"1";
"B"
$PN"2"20;
"A"
$PN"1"12;
%"LM75BD"
"1","(2150,1375)","0","pure_quanta","I164";
;
PART_NUMBER"AL0075BD000"
PART_TYPE"SMLF"
MATERIAL"IC"
VALUE"LM75BD"
LOCATION"U270"
CDS_LIB"pure_quanta"
CDS_LMAN_SYM_OUTLINE"-225,325,225,-325"
NEEDS_NO_SIZE"TRUE"
$SEC"1"
CDS_SEC"1";
"VCC"
$PN"8"12;
"A0"
$PN"7"67;
"A1"
$PN"6"65;
"A2"
$PN"5"66;
"GND"
$PN"4"16;
"OS"
$PN"3"39;
"SCL"
$PN"2"40;
"SDA"
$PN"1"38;
%"LM75BD"
"1","(2100,-100)","0","pure_quanta","I165";
;
PART_NUMBER"AL0075BD000"
PART_TYPE"SMLF"
MATERIAL"IC"
VALUE"LM75BD"
LOCATION"U271"
CDS_LMAN_SYM_OUTLINE"-225,325,225,-325"
CDS_LIB"pure_quanta"
NEEDS_NO_SIZE"TRUE"
$SEC"1"
CDS_SEC"1";
"VCC"
$PN"8"8;
"A0"
$PN"7"42;
"A1"
$PN"6"63;
"A2"
$PN"5"62;
"GND"
$PN"4"15;
"OS"
$PN"3"47;
"SCL"
$PN"2"43;
"SDA"
$PN"1"44;
%"LM75BD"
"1","(2075,-1575)","0","pure_quanta","I166";
;
PART_NUMBER"AL0075BD000"
VALUE"LM75BD"
MATERIAL"IC"
PART_TYPE"SMLF"
LOCATION"U272"
CDS_LIB"pure_quanta"
CDS_LMAN_SYM_OUTLINE"-225,325,225,-325"
NEEDS_NO_SIZE"TRUE"
$SEC"1"
CDS_SEC"1";
"VCC"
$PN"8"7;
"A0"
$PN"7"59;
"A1"
$PN"6"57;
"A2"
$PN"5"58;
"GND"
$PN"4"14;
"OS"
$PN"3"45;
"SCL"
$PN"2"56;
"SDA"
$PN"1"46;
%"LM75BD"
"1","(2025,-3050)","0","pure_quanta","I167";
;
PART_NUMBER"AL0075BD000"
PART_TYPE"SMLF"
VALUE"LM75BD"
MATERIAL"IC"
LOCATION"U273"
NEEDS_NO_SIZE"TRUE"
CDS_LMAN_SYM_OUTLINE"-225,325,225,-325"
CDS_LIB"pure_quanta"
$SEC"1"
CDS_SEC"1";
"VCC"
$PN"8"5;
"A0"
$PN"7"51;
"A1"
$PN"6"52;
"A2"
$PN"5"53;
"GND"
$PN"4"13;
"OS"
$PN"3"54;
"SCL"
$PN"2"49;
"SDA"
$PN"1"50;
%"Q_RES"
"2","(-200,1800)","0","pure_quanta","I168";
;
PART_NUMBER"CS42002FB05"
VALUE"200K"
PACK_TYPE"0402LF"
MATERIAL"CHIP"
WATTAGE"1/16W"
TOLERANCE"1%"
LOCATION"R4211"
CDS_LIB"pure_quanta"
$SEC"1"
CDS_SEC"1";
"A"
$PN"1"3;
"B"
$PN"2"37;
%"Q_RES"
"2","(-250,325)","0","pure_quanta","I169";
;
PART_NUMBER"CS42002FB05"
MATERIAL"EMPTY"
WATTAGE"1/16W"
PACK_TYPE"0402LF"
TOLERANCE"1%"
VALUE"200K"
LOCATION"R4209"
CDS_LIB"pure_quanta"
$SEC"1"
CDS_SEC"1";
"A"
$PN"1"2;
"B"
$PN"2"35;
%"UNIVERSAL_GND"
"1","(2600,1725)","0","logical_power","I17";
;
CDS_LIB"logical_power"
HDL_POWER"GND";
"A"20;
%"Q_RES"
"2","(-250,-1175)","0","pure_quanta","I170";
;
PART_NUMBER"CS42002FB05"
VALUE"200K"
TOLERANCE"1%"
PACK_TYPE"0402LF"
WATTAGE"1/16W"
MATERIAL"EMPTY"
LOCATION"R4210"
CDS_LIB"pure_quanta"
$SEC"1"
CDS_SEC"1";
"A"
$PN"1"6;
"B"
$PN"2"34;
%"Q_RES"
"2","(-350,-2625)","0","pure_quanta","I171";
;
PART_NUMBER"CS42002FB05"
PACK_TYPE"0402LF"
MATERIAL"EMPTY"
WATTAGE"1/16W"
TOLERANCE"1%"
VALUE"200K"
LOCATION"R4208"
CDS_LIB"pure_quanta"
$SEC"1"
CDS_SEC"1";
"A"
$PN"1"1;
"B"
$PN"2"33;
%"UNIVERSAL_GND"
"1","(1675,1025)","0","logical_power","I21";
;
CDS_LIB"logical_power"
HDL_POWER"GND";
"A"16;
%"Q_RES"
"1","(350,1450)","0","pure_quanta","I77";
;
PART_NUMBER"CS03322FB03"
VALUE"33.2"
MATERIAL"CHIP"
WATTAGE"1/16W"
TOLERANCE"1%"
PACK_TYPE"0402LF"
$LOCATION"R4180"
CDS_LIB"pure_quanta"
CDS_LOCATION"R4180"
$SEC"1"
CDS_SEC"1";
"B"
$PN"2"40;
"A"
$PN"1"68;
%"Q_RES"
"1","(350,1600)","0","pure_quanta","I78";
;
PART_NUMBER"CS03322FB03"
VALUE"33.2"
TOLERANCE"1%"
MATERIAL"CHIP"
PACK_TYPE"0402LF"
WATTAGE"1/16W"
$LOCATION"R4183"
CDS_LIB"pure_quanta"
CDS_LOCATION"R4183"
$SEC"1"
CDS_SEC"1";
"B"
$PN"2"38;
"A"
$PN"1"36;
%"Q_RES"
"1","(350,1300)","0","pure_quanta","I79";
;
PART_NUMBER"CS00002JB13"
MATERIAL"CHIP"
PACK_TYPE"0402LF"
VALUE"0"
$LOCATION"R4215"
TOLERANCE"5%"
WATTAGE"1/16W"
CDS_LIB"pure_quanta"
CDS_LOCATION"R4215"
$SEC"1"
CDS_SEC"1";
"B"
$PN"2"39;
"A"
$PN"1"37;
%"UNIVERSAL_GND"
"1","(4200,775)","0","logical_power","I80";
;
CDS_LIB"logical_power"
HDL_POWER"GND";
"A"18;
%"Q_RES"
"2","(4200,1000)","0","pure_quanta","I81";
;
PART_NUMBER"CS21002FB06"
MATERIAL"CHIP"
PACK_TYPE"0402LF"
VALUE"1K"
WATTAGE"1/16W"
TOLERANCE"1%"
$LOCATION"R4199"
CDS_LIB"pure_quanta"
CDS_LOCATION"R4199"
$SEC"1"
CDS_SEC"1";
"A"
$PN"1"65;
"B"
$PN"2"18;
%"Q_RES"
"2","(4200,1600)","0","pure_quanta","I82";
;
PART_NUMBER"CS21002FB06"
TOLERANCE"1%"
WATTAGE"1/16W"
VALUE"1K"
MATERIAL"EMPTY"
PACK_TYPE"0402LF"
$LOCATION"R4198"
CDS_LIB"pure_quanta"
CDS_LOCATION"R4198"
$SEC"1"
CDS_SEC"1";
"A"
$PN"1"9;
"B"
$PN"2"65;
%"UNIVERSAL_POWER"
"1","(4450,2025)","0","logical_power","I83";
;
HDL_POWER"P3V3_AUX"
CDS_LIB"logical_power";
"A"9;
%"UNIVERSAL_GND"
"1","(4450,775)","0","logical_power","I84";
;
CDS_LIB"logical_power"
HDL_POWER"GND";
"A"17;
%"Q_RES"
"2","(4450,1000)","0","pure_quanta","I85";
;
PART_NUMBER"CS21002FB06"
MATERIAL"CHIP"
PACK_TYPE"0402LF"
WATTAGE"1/16W"
VALUE"1K"
TOLERANCE"1%"
$LOCATION"R4207"
CDS_LIB"pure_quanta"
CDS_LOCATION"R4207"
$SEC"1"
CDS_SEC"1";
"A"
$PN"1"67;
"B"
$PN"2"17;
%"Q_RES"
"2","(4450,1600)","0","pure_quanta","I86";
;
PART_NUMBER"CS21002FB06"
WATTAGE"1/16W"
VALUE"1K"
PACK_TYPE"0402LF"
TOLERANCE"1%"
MATERIAL"EMPTY"
$LOCATION"R4206"
CDS_LIB"pure_quanta"
CDS_LOCATION"R4206"
$SEC"1"
CDS_SEC"1";
"A"
$PN"1"9;
"B"
$PN"2"67;
%"Q_RES"
"2","(3950,1000)","0","pure_quanta","I89";
;
PART_NUMBER"CS21002FB06"
MATERIAL"CHIP"
PACK_TYPE"0402LF"
VALUE"1K"
WATTAGE"1/16W"
TOLERANCE"1%"
$LOCATION"R4191"
CDS_LIB"pure_quanta"
CDS_LOCATION"R4191"
$SEC"1"
CDS_SEC"1";
"A"
$PN"1"66;
"B"
$PN"2"19;
%"UNIVERSAL_GND"
"1","(3950,775)","0","logical_power","I90";
;
CDS_LIB"logical_power"
HDL_POWER"GND";
"A"19;
%"Q_RES"
"2","(3950,1600)","0","pure_quanta","I91";
;
PART_NUMBER"CS21002FB06"
TOLERANCE"1%"
WATTAGE"1/16W"
VALUE"1K"
MATERIAL"EMPTY"
PACK_TYPE"0402LF"
$LOCATION"R4190"
CDS_LIB"pure_quanta"
CDS_LOCATION"R4190"
$SEC"1"
CDS_SEC"1";
"A"
$PN"1"9;
"B"
$PN"2"66;
%"UNIVERSAL_POWER"
"1","(4400,550)","0","logical_power","I93";
;
HDL_POWER"P3V3_AUX"
CDS_LIB"logical_power";
"A"10;
%"Q_RES"
"2","(4400,125)","0","pure_quanta","I94";
;
PART_NUMBER"CS21002FB06"
WATTAGE"1/16W"
VALUE"1K"
PACK_TYPE"0402LF"
TOLERANCE"1%"
MATERIAL"EMPTY"
$LOCATION"R4204"
CDS_LIB"pure_quanta"
CDS_LOCATION"R4204"
$SEC"1"
CDS_SEC"1";
"A"
$PN"1"10;
"B"
$PN"2"42;
%"Q_RES"
"2","(4150,125)","0","pure_quanta","I95";
;
PART_NUMBER"CS21002FB06"
TOLERANCE"1%"
WATTAGE"1/16W"
VALUE"1K"
MATERIAL"EMPTY"
PACK_TYPE"0402LF"
$LOCATION"R4196"
CDS_LIB"pure_quanta"
CDS_LOCATION"R4196"
$SEC"1"
CDS_SEC"1";
"A"
$PN"1"10;
"B"
$PN"2"63;
%"Q_RES"
"2","(4400,-475)","0","pure_quanta","I96";
;
PART_NUMBER"CS21002FB06"
MATERIAL"CHIP"
PACK_TYPE"0402LF"
WATTAGE"1/16W"
VALUE"1K"
TOLERANCE"1%"
$LOCATION"R4205"
CDS_LIB"pure_quanta"
CDS_LOCATION"R4205"
$SEC"1"
CDS_SEC"1";
"A"
$PN"1"42;
"B"
$PN"2"21;
%"UNIVERSAL_GND"
"1","(4400,-700)","0","logical_power","I97";
;
CDS_LIB"logical_power"
HDL_POWER"GND";
"A"21;
%"Q_RES"
"2","(4150,-475)","0","pure_quanta","I98";
;
PART_NUMBER"CS21002FB06"
TOLERANCE"1%"
MATERIAL"CHIP"
PACK_TYPE"0402LF"
VALUE"1K"
WATTAGE"1/16W"
$LOCATION"R4197"
CDS_LIB"pure_quanta"
CDS_LOCATION"R4197"
$SEC"1"
CDS_SEC"1";
"A"
$PN"1"63;
"B"
$PN"2"22;
%"UNIVERSAL_GND"
"1","(4150,-700)","0","logical_power","I99";
;
CDS_LIB"logical_power"
HDL_POWER"GND";
"A"22;
END.
